# S9S_MB_2U (Grand Teton) — schematic netlist excerpt (pin names and nets, part order shuffled) for the footprints in the layout excerpt that follows; sources: Cadence DE-HDL packaged netlist, KiCad conversion of 03242023_DA0F0TMBIJ0_F0T_Motherboard_J_brd_V01_OCP.brd

R3079  Q_RES  130 1% CHIP  pkg 0402LF  page 256 : A = LED_RST_PLD_CPU0_DRAM_EF_N ; B = P3V3_AUX
C731  Q_CAP_DIFFBUS  DIFF BUS_0.22UF 6.3V 20% X6S  pkg C0201  page 176 : \1\ = P5E_CPU1_PE0_TX_C_DP<5> ; \2\ = P5E_CPU1_PE0_TX_DP<5>
R3045  Q_RES  0 5% CHIP  pkg 0402LF  page 215 : A = IRQ_UV_DETECT_N ; B = IRQ_UV_DETECT_R_N

(kicad_pcb
	(version 20260206)
	(generator "pcbnew")
	(generator_version "10.0")
	(general
		(thickness 1.6)
		(legacy_teardrops no)
	)
	(paper "A4")
	(title_block
		(title "03242023_DA0F0TMBIJ0_F0T_Motherboard_J_brd_V01_OCP.brd")
		(comment 1 "Grand Teton / footprints 474-476 of 6105")
	)
	(layers
		(0 "F.Cu" signal "TOP")
		(4 "In1.Cu" signal "GND")
		(6 "In2.Cu" signal "IN1")
		(8 "In3.Cu" signal "GND1")
		(10 "In4.Cu" signal "IN2")
		(12 "In5.Cu" signal "GND2")
		(14 "In6.Cu" signal "IN3")
		(16 "In7.Cu" signal "GND3")
		(18 "In8.Cu" signal "VCC")
		(20 "In9.Cu" signal "VCC1")
		(22 "In10.Cu" signal "GND4")
		(24 "In11.Cu" signal "IN4")
		(26 "In12.Cu" signal "GND5")
		(28 "In13.Cu" signal "IN5")
		(30 "In14.Cu" signal "GND6")
		(32 "In15.Cu" signal "IN6")
		(34 "In16.Cu" signal "GND7")
		(2 "B.Cu" signal "BOTTOM")
		(9 "F.Adhes" user "F.Adhesive")
		(11 "B.Adhes" user "B.Adhesive")
		(13 "F.Paste" user "Package Geometry/Pastemask Top")
		(15 "B.Paste" user "Package Geometry/Pastemask Bottom")
		(5 "F.SilkS" user "Ref Des/Silkscreen Top")
		(7 "B.SilkS" user "Ref Des/Silkscreen Bottom")
		(1 "F.Mask" user "Board Geometry/Soldermask Top")
		(3 "B.Mask" user "Board Geometry/Soldermask Bottom")
		(17 "Dwgs.User" user "User.Drawings")
		(19 "Cmts.User" user "User.Comments")
		(21 "Eco1.User" user "User.Eco1")
		(23 "Eco2.User" user "User.Eco2")
		(25 "Edge.Cuts" user "Board Geometry/Outline")
		(27 "Margin" user)
		(31 "F.CrtYd" user "Package Geometry/Place Bound Top")
		(29 "B.CrtYd" user "Package Geometry/Place Bound Bottom")
		(35 "F.Fab" user "Ref Des/Assembly Top")
		(33 "B.Fab" user "Ref Des/Assembly Bottom")
	)
	(footprint ""
		(layer "F.Cu")
		(at 74.106786 -65.082674 -90)
		(property "Reference" "R3079"
			(at 0 0 270)
			(layer "F.SilkS")
			(hide yes)
			(effects
				(font
					(size 1.27 1.27)
				)
			)
		)
		(property "Value" ""
			(at 0 0 270)
			(layer "F.Fab")
			(effects
				(font
					(size 1.27 1.27)
				)
			)
		)
		(duplicate_pad_numbers_are_jumpers no)
		(fp_line
			(start -0.7874 0.4064)
			(end -0.7874 -0.4064)
			(stroke
				(width 0.1524)
				(type default)
			)
			(layer "F.SilkS")
		)
		(fp_line
			(start 0.7874 0.4064)
			(end -0.7874 0.4064)
			(stroke
				(width 0.1524)
				(type default)
			)
			(layer "F.SilkS")
		)
		(fp_line
			(start -0.7874 -0.4064)
			(end 0.7874 -0.4064)
			(stroke
				(width 0.1524)
				(type default)
			)
			(layer "F.SilkS")
		)
		(fp_line
			(start 0.7874 -0.4064)
			(end 0.7874 0.4064)
			(stroke
				(width 0.1524)
				(type default)
			)
			(layer "F.SilkS")
		)
		(fp_line
			(start -0.67945 0.3048)
			(end -0.67945 -0.305054)
			(stroke
				(width 0.1)
				(type default)
			)
			(layer "F.Fab")
		)
		(fp_line
			(start -0.12065 0.3048)
			(end -0.67945 0.3048)
			(stroke
				(width 0.1)
				(type default)
			)
			(layer "F.Fab")
		)
		(fp_line
			(start 0.120396 0.3048)
			(end 0.120396 0.2794)
			(stroke
				(width 0.1)
				(type default)
			)
			(layer "F.Fab")
		)
		(fp_line
			(start 0.67945 0.3048)
			(end 0.120396 0.3048)
			(stroke
				(width 0.1)
				(type default)
			)
			(layer "F.Fab")
		)
		(fp_line
			(start -0.12065 0.2794)
			(end -0.12065 0.3048)
			(stroke
				(width 0.1)
				(type default)
			)
			(layer "F.Fab")
		)
		(fp_line
			(start 0.120396 0.2794)
			(end -0.12065 0.2794)
			(stroke
				(width 0.1)
				(type default)
			)
			(layer "F.Fab")
		)
		(fp_line
			(start -0.12065 -0.2794)
			(end 0.12065 -0.2794)
			(stroke
				(width 0.1)
				(type default)
			)
			(layer "F.Fab")
		)
		(fp_line
			(start 0.12065 -0.2794)
			(end 0.12065 -0.3048)
			(stroke
				(width 0.1)
				(type default)
			)
			(layer "F.Fab")
		)
		(fp_line
			(start 0.12065 -0.3048)
			(end 0.67945 -0.3048)
			(stroke
				(width 0.1)
				(type default)
			)
			(layer "F.Fab")
		)
		(fp_line
			(start 0.67945 -0.3048)
			(end 0.67945 0.3048)
			(stroke
				(width 0.1)
				(type default)
			)
			(layer "F.Fab")
		)
		(fp_line
			(start -0.67945 -0.305054)
			(end -0.12065 -0.305054)
			(stroke
				(width 0.1)
				(type default)
			)
			(layer "F.Fab")
		)
		(fp_line
			(start -0.12065 -0.305054)
			(end -0.12065 -0.2794)
			(stroke
				(width 0.1)
				(type default)
			)
			(layer "F.Fab")
		)
		(pad "1" smd circle
			(at -0.40005 0 270)
			(size 0 0)
			(layers "F.Cu" "F.Mask" "F.Paste")
			(net "LED_RST_PLD_CPU0_DRAM_EF_N")
		)
		(pad "2" smd circle
			(at 0.40005 0 270)
			(size 0 0)
			(layers "F.Cu" "F.Mask" "F.Paste")
			(net "P3V3_AUX")
		)
	)
	(footprint ""
		(layer "F.Cu")
		(at 79.501238 -402.371052 -90)
		(property "Reference" "C731"
			(at 0 0 270)
			(layer "F.SilkS")
			(hide yes)
			(effects
				(font
					(size 1.27 1.27)
				)
			)
		)
		(property "Value" ""
			(at 0 0 270)
			(layer "F.Fab")
			(effects
				(font
					(size 1.27 1.27)
				)
			)
		)
		(duplicate_pad_numbers_are_jumpers no)
		(fp_line
			(start -0.299974 0.150114)
			(end -0.299974 -0.150114)
			(stroke
				(width 0.1)
				(type default)
			)
			(layer "F.Fab")
		)
		(fp_line
			(start 0.299974 0.150114)
			(end -0.299974 0.150114)
			(stroke
				(width 0.1)
				(type default)
			)
			(layer "F.Fab")
		)
		(fp_line
			(start -0.299974 -0.150114)
			(end 0.299974 -0.150114)
			(stroke
				(width 0.1)
				(type default)
			)
			(layer "F.Fab")
		)
		(fp_line
			(start 0.299974 -0.150114)
			(end 0.299974 0.150114)
			(stroke
				(width 0.1)
				(type default)
			)
			(layer "F.Fab")
		)
		(pad "1" smd rect
			(at -0.2667 0 270)
			(size 0.3048 0.381)
			(layers "F.Cu" "F.Mask" "F.Paste")
			(net "P5E_CPU1_PE0_TX_C_DP<5>")
		)
		(pad "2" smd rect
			(at 0.2667 0 270)
			(size 0.3048 0.381)
			(layers "F.Cu" "F.Mask" "F.Paste")
			(net "P5E_CPU1_PE0_TX_DP<5>")
		)
	)
	(footprint ""
		(layer "F.Cu")
		(at 193.60388 -103.685848 180)
		(property "Reference" "R3045"
			(at 0 0 180)
			(layer "F.SilkS")
			(hide yes)
			(effects
				(font
					(size 1.27 1.27)
				)
			)
		)
		(property "Value" ""
			(at 0 0 180)
			(layer "F.Fab")
			(effects
				(font
					(size 1.27 1.27)
				)
			)
		)
		(duplicate_pad_numbers_are_jumpers no)
		(fp_line
			(start 0.7874 0.4064)
			(end -0.7874 0.4064)
			(stroke
				(width 0.1524)
				(type default)
			)
			(layer "F.SilkS")
		)
		(fp_line
			(start 0.7874 -0.4064)
			(end 0.7874 0.4064)
			(stroke
				(width 0.1524)
				(type default)
			)
			(layer "F.SilkS")
		)
		(fp_line
			(start -0.7874 0.4064)
			(end -0.7874 -0.4064)
			(stroke
				(width 0.1524)
				(type default)
			)
			(layer "F.SilkS")
		)
		(fp_line
			(start -0.7874 -0.4064)
			(end 0.7874 -0.4064)
			(stroke
				(width 0.1524)
				(type default)
			)
			(layer "F.SilkS")
		)
		(fp_line
			(start 0.67945 0.3048)
			(end 0.120396 0.3048)
			(stroke
				(width 0.1)
				(type default)
			)
			(layer "F.Fab")
		)
		(fp_line
			(start 0.67945 -0.3048)
			(end 0.67945 0.3048)
			(stroke
				(width 0.1)
				(type default)
			)
			(layer "F.Fab")
		)
		(fp_line
			(start 0.12065 -0.2794)
			(end 0.12065 -0.3048)
			(stroke
				(width 0.1)
				(type default)
			)
			(layer "F.Fab")
		)
		(fp_line
			(start 0.12065 -0.3048)
			(end 0.67945 -0.3048)
			(stroke
				(width 0.1)
				(type default)
			)
			(layer "F.Fab")
		)
		(fp_line
			(start 0.120396 0.3048)
			(end 0.120396 0.2794)
			(stroke
				(width 0.1)
				(type default)
			)
			(layer "F.Fab")
		)
		(fp_line
			(start 0.120396 0.2794)
			(end -0.12065 0.2794)
			(stroke
				(width 0.1)
				(type default)
			)
			(layer "F.Fab")
		)
		(fp_line
			(start -0.12065 0.3048)
			(end -0.67945 0.3048)
			(stroke
				(width 0.1)
				(type default)
			)
			(layer "F.Fab")
		)
		(fp_line
			(start -0.12065 0.2794)
			(end -0.12065 0.3048)
			(stroke
				(width 0.1)
				(type default)
			)
			(layer "F.Fab")
		)
		(fp_line
			(start -0.12065 -0.2794)
			(end 0.12065 -0.2794)
			(stroke
				(width 0.1)
				(type default)
			)
			(layer "F.Fab")
		)
		(fp_line
			(start -0.12065 -0.305054)
			(end -0.12065 -0.2794)
			(stroke
				(width 0.1)
				(type default)
			)
			(layer "F.Fab")
		)
		(fp_line
			(start -0.67945 0.3048)
			(end -0.67945 -0.305054)
			(stroke
				(width 0.1)
				(type default)
			)
			(layer "F.Fab")
		)
		(fp_line
			(start -0.67945 -0.305054)
			(end -0.12065 -0.305054)
			(stroke
				(width 0.1)
				(type default)
			)
			(layer "F.Fab")
		)
		(pad "1" smd circle
			(at -0.40005 0 180)
			(size 0 0)
			(layers "F.Cu" "F.Mask" "F.Paste")
			(net "IRQ_UV_DETECT_N")
		)
		(pad "2" smd circle
			(at 0.40005 0 180)
			(size 0 0)
			(layers "F.Cu" "F.Mask" "F.Paste")
			(net "IRQ_UV_DETECT_R_N")
		)
	)
)
